#ISCELL
  mstr_misc dns *
  *
#ISCELL
  mstr_symbols intel_corp_bpage *
  *
#CELL
  mstr_discrete res *
  page164_i100
#CELL
  mstr_discrete res *
  page164_i101
#CELL
  mstr_discrete res *
  page164_i11
#ISCELL
  mstr_symbols p3v3_stby *
  page164_i12
#ISCELL
  mstr_standard offpage *
  page164_i15
#ISCELL
  mstr_standard offpage *
  page164_i16
#ISCELL
  mstr_standard offpage *
  page164_i17
#ISCELL
  mstr_standard offpage *
  page164_i18
#ISCELL
  mstr_standard offpage *
  page164_i2
#CELL
  mstr_discrete res *
  page164_i21
#ISCELL
  mstr_symbols p3v3_stby *
  page164_i26
#ISCELL
  mstr_standard offpage *
  page164_i3
#ISCELL
  mstr_standard offpage *
  page164_i30
#ISCELL
  mstr_symbols gnd *
  page164_i31
#CELL
  mstr_discrete res *
  page164_i32
#CELL
  mstr_discrete res *
  page164_i34
#CELL
  mstr_discrete res *
  page164_i37
#ISCELL
  mstr_standard offpage *
  page164_i4
#CELL
  mstr_discrete res *
  page164_i40
#CELL
  mstr_discrete res *
  page164_i41
#CELL
  mstr_discrete res *
  page164_i43
#CELL
  mstr_discrete res *
  page164_i46
#CELL
  mstr_discrete res *
  page164_i47
#CELL
  mstr_discrete res *
  page164_i48
#CELL
  mstr_discrete res *
  page164_i51
#CELL
  mstr_discrete res *
  page164_i53
#ISCELL
  mstr_symbols gnd *
  page164_i55
#ISCELL
  mstr_standard offpage *
  page164_i56
#ISCELL
  mstr_symbols p3v3_stby *
  page164_i65
#CELL
  dev_discrete cap_a *
  page164_i66
#ISCELL
  mstr_symbols gnd *
  page164_i67
#CELL
  mstr_discrete res *
  page164_i7
#CELL
  mstr_discrete res *
  page164_i76
#CELL
  mstr_discrete res *
  page164_i78
#ISCELL
  mstr_symbols p3v3_stby *
  page164_i81
#ISCELL
  mstr_symbols gnd *
  page164_i82
#ISCELL
  mstr_symbols gnd *
  page164_i84
#ISCELL
  mstr_symbols gnd *
  page164_i86
#CELL
  mstr_discrete res *
  page164_i87
#ISCELL
  mstr_symbols p3v3_stby *
  page164_i88
#ISCELL
  mstr_standard offpage *
  page164_i89
#ISCELL
  mstr_symbols gnd *
  page164_i9
#ISCELL
  mstr_standard offpage *
  page164_i90
#ISCELL
  mstr_standard offpage *
  page164_i91
#ISCELL
  mstr_standard offpage *
  page164_i92
#CELL
  mstr_discrete res *
  page164_i93
#CELL
  mstr_discrete res *
  page164_i94
#CELL
  mstr_discrete res *
  page164_i95
#CELL
  mstr_discrete res *
  page164_i96
#CELL
  w_hdl pca9554pwr-gp *
  page164_i97
#ISCELL
  mstr_standard offpage *
  page164_i99
